(kicad_pcb
	(version 20241229)
	(generator "pcbnew")
	(generator_version "9.0")
	(general
		(thickness 1.61)
		(legacy_teardrops no)
	)
	(paper "A3")
	(title_block
		(title "RDIMM DDR5 Tester")
		(date "2026-05-21")
		(rev "2.2.0")
		(company "Antmicro")
		(comment 9 "footprints 543-547 of 796")
	)
	(layers
		(0 "F.Cu" signal)
		(4 "In1.Cu" power)
		(6 "In2.Cu" mixed)
		(8 "In3.Cu" power)
		(10 "In4.Cu" mixed)
		(12 "In5.Cu" power)
		(14 "In6.Cu" mixed)
		(16 "In7.Cu" power)
		(18 "In8.Cu" power)
		(20 "In9.Cu" mixed)
		(22 "In10.Cu" power)
		(2 "B.Cu" signal)
		(9 "F.Adhes" user "F.Adhesive")
		(11 "B.Adhes" user "B.Adhesive")
		(13 "F.Paste" user)
		(15 "B.Paste" user)
		(5 "F.SilkS" user "F.Silkscreen")
		(7 "B.SilkS" user "B.Silkscreen")
		(1 "F.Mask" user)
		(3 "B.Mask" user)
		(17 "Dwgs.User" user "User.Drawings")
		(19 "Cmts.User" user "User.Comments")
		(21 "Eco1.User" user "User.Eco1")
		(23 "Eco2.User" user "User.Eco2")
		(25 "Edge.Cuts" user)
		(27 "Margin" user)
		(31 "F.CrtYd" user "F.Courtyard")
		(29 "B.CrtYd" user "B.Courtyard")
		(35 "F.Fab" user)
		(33 "B.Fab" user)
	)
	(footprint "antmicro-footprints:C_0402_1005Metric"
		(layer "B.Cu")
		(at 207.321 137.0045)
		(descr "Capacitor SMD 0402")
		(tags "capacitor SMD 0402")
		(property "Reference" "C330"
			(at 2.279 0 0)
			(layer "B.SilkS")
			(effects
				(font
					(size 0.7 0.7)
					(thickness 0.15)
				)
				(justify mirror)
			)
		)
		(property "Value" "C_100n_0402"
			(at -1.022927 -2.155213 0)
			(layer "B.Fab")
			(effects
				(font
					(size 0.7 0.7)
					(thickness 0.15)
				)
				(justify right top mirror)
			)
		)
		(property "Datasheet" "https://www.murata.com/products/productdetail?partno=GRM155R61H104KE14%23"
			(at 0 0 0)
			(layer "B.Fab")
			(hide yes)
			(effects
				(font
					(size 1.27 1.27)
					(thickness 0.15)
				)
				(justify mirror)
			)
		)
		(property "Manufacturer" "Murata"
			(at 0 0 180)
			(unlocked yes)
			(layer "B.Fab")
			(hide yes)
			(effects
				(font
					(size 1 1)
					(thickness 0.15)
				)
				(justify mirror)
			)
		)
		(property "MPN" "GRM155R61H104KE14D"
			(at 0 0 180)
			(unlocked yes)
			(layer "B.Fab")
			(hide yes)
			(effects
				(font
					(size 1 1)
					(thickness 0.15)
				)
				(justify mirror)
			)
		)
		(property "Val" "100n"
			(at 0 0 180)
			(unlocked yes)
			(layer "B.Fab")
			(hide yes)
			(effects
				(font
					(size 1 1)
					(thickness 0.15)
				)
				(justify mirror)
			)
		)
		(property "License" "Apache-2.0"
			(at 0 0 180)
			(unlocked yes)
			(layer "B.Fab")
			(hide yes)
			(effects
				(font
					(size 1 1)
					(thickness 0.15)
				)
				(justify mirror)
			)
		)
		(property "Author" "Antmicro"
			(at 0 0 180)
			(unlocked yes)
			(layer "B.Fab")
			(hide yes)
			(effects
				(font
					(size 1 1)
					(thickness 0.15)
				)
				(justify mirror)
			)
		)
		(property "Voltage" "50V"
			(at 0 0 180)
			(unlocked yes)
			(layer "B.Fab")
			(hide yes)
			(effects
				(font
					(size 1 1)
					(thickness 0.15)
				)
				(justify mirror)
			)
		)
		(property "Dielectric" "X5R"
			(at 0 0 180)
			(unlocked yes)
			(layer "B.Fab")
			(hide yes)
			(effects
				(font
					(size 1 1)
					(thickness 0.15)
				)
				(justify mirror)
			)
		)
		(sheetname "/Supply/")
		(sheetfile "supply.kicad_sch")
		(attr smd)
		(fp_rect
			(start -0.925 0.47)
			(end 0.925 -0.47)
			(stroke
				(width 0.05)
				(type default)
			)
			(fill no)
			(layer "B.CrtYd")
		)
		(fp_line
			(start -0.494 -0.248)
			(end -0.494 0.25)
			(stroke
				(width 0.15)
				(type solid)
			)
			(layer "B.Fab")
		)
		(fp_line
			(start -0.494 0.25)
			(end 0.504 0.25)
			(stroke
				(width 0.15)
				(type solid)
			)
			(layer "B.Fab")
		)
		(fp_line
			(start 0.504 -0.248)
			(end -0.494 -0.248)
			(stroke
				(width 0.15)
				(type solid)
			)
			(layer "B.Fab")
		)
		(fp_line
			(start 0.504 0.25)
			(end 0.504 -0.248)
			(stroke
				(width 0.15)
				(type solid)
			)
			(layer "B.Fab")
		)
		(fp_text user "License: Apache-2.0"
			(at -0.939 -5.799 0)
			(layer "B.Fab")
			(effects
				(font
					(size 0.7 0.7)
					(thickness 0.15)
				)
				(justify right top mirror)
			)
		)
		(fp_text user "Author: Antmicro"
			(at -0.939 -3.399 0)
			(layer "B.Fab")
			(effects
				(font
					(size 0.7 0.7)
					(thickness 0.15)
				)
				(justify right top mirror)
			)
		)
		(fp_text user "${REFERENCE}"
			(at -0.939 -4.599 0)
			(layer "B.Fab")
			(effects
				(font
					(size 0.7 0.7)
					(thickness 0.15)
				)
				(justify right top mirror)
			)
		)
		(pad "1" smd roundrect
			(at -0.48 0)
			(size 0.59 0.64)
			(layers "B.Cu" "B.Mask" "B.Paste")
			(roundrect_rratio 0.25)
			(net 1 "GND")
			(pintype "passive")
		)
		(pad "2" smd roundrect
			(at 0.48 0)
			(size 0.59 0.64)
			(layers "B.Cu" "B.Mask" "B.Paste")
			(roundrect_rratio 0.25)
			(net 687 "VDDQ")
			(pintype "passive")
		)
	)
	(footprint "antmicro-footprints:C_0603_1608Metric"
		(layer "B.Cu")
		(at 188.5 159.2 90)
		(descr "Capacitor SMD 0603")
		(tags "capacitor 0603")
		(property "Reference" "C63"
			(at 9.85 -30.75 90)
			(layer "B.SilkS")
			(effects
				(font
					(size 0.7 0.7)
					(thickness 0.15)
				)
				(justify right bottom mirror)
			)
		)
		(property "Value" "C_47u_0603"
			(at -1.42757 -1.770288 90)
			(layer "B.Fab")
			(effects
				(font
					(size 0.7 0.7)
					(thickness 0.15)
				)
				(justify right bottom mirror)
			)
		)
		(property "Datasheet" "https://www.murata.com/products/productdetail?partno=GRM188R60J476ME15%23"
			(at 0 0 90)
			(layer "F.Fab")
			(hide yes)
			(effects
				(font
					(size 1.27 1.27)
					(thickness 0.15)
				)
			)
		)
		(property "Manufacturer" "Murata"
			(at 0 0 90)
			(unlocked yes)
			(layer "B.Fab")
			(hide yes)
			(effects
				(font
					(size 1 1)
					(thickness 0.15)
				)
				(justify mirror)
			)
		)
		(property "MPN" "GRM188R60J476ME15D"
			(at 0 0 90)
			(unlocked yes)
			(layer "B.Fab")
			(hide yes)
			(effects
				(font
					(size 1 1)
					(thickness 0.15)
				)
				(justify mirror)
			)
		)
		(property "Val" "47u"
			(at 0 0 90)
			(unlocked yes)
			(layer "B.Fab")
			(hide yes)
			(effects
				(font
					(size 1 1)
					(thickness 0.15)
				)
				(justify mirror)
			)
		)
		(property "License" "Apache-2.0"
			(at 0 0 90)
			(unlocked yes)
			(layer "B.Fab")
			(hide yes)
			(effects
				(font
					(size 1 1)
					(thickness 0.15)
				)
				(justify mirror)
			)
		)
		(property "Author" "Antmicro"
			(at 0 0 90)
			(unlocked yes)
			(layer "B.Fab")
			(hide yes)
			(effects
				(font
					(size 1 1)
					(thickness 0.15)
				)
				(justify mirror)
			)
		)
		(property "Voltage" ""
			(at 0 0 90)
			(unlocked yes)
			(layer "B.Fab")
			(hide yes)
			(effects
				(font
					(size 1 1)
					(thickness 0.15)
				)
				(justify mirror)
			)
		)
		(property "Dielectric" ""
			(at 0 0 90)
			(unlocked yes)
			(layer "B.Fab")
			(hide yes)
			(effects
				(font
					(size 1 1)
					(thickness 0.15)
				)
				(justify mirror)
			)
		)
		(sheetname "/FPGA power/")
		(sheetfile "fpga-power.kicad_sch")
		(attr smd)
		(fp_line
			(start -0.15 -0.4)
			(end 0.15 -0.4)
			(stroke
				(width 0.15)
				(type solid)
			)
			(layer "B.SilkS")
		)
		(fp_line
			(start -0.15 0.4)
			(end 0.15 0.4)
			(stroke
				(width 0.15)
				(type solid)
			)
			(layer "B.SilkS")
		)
		(fp_rect
			(start -1.25 0.65)
			(end 1.25 -0.65)
			(stroke
				(width 0.05)
				(type solid)
			)
			(fill no)
			(layer "B.CrtYd")
		)
		(fp_rect
			(start -0.8 0.4)
			(end 0.8 -0.4)
			(stroke
				(width 0.15)
				(type solid)
			)
			(fill no)
			(layer "B.Fab")
		)
		(fp_text user "Author: Antmicro"
			(at -1.682 -4.894 270)
			(layer "B.Fab")
			(effects
				(font
					(size 0.7 0.7)
					(thickness 0.15)
				)
				(justify left bottom mirror)
			)
		)
		(fp_text user "${REFERENCE}"
			(at -1.682 -3.895 270)
			(layer "B.Fab")
			(effects
				(font
					(size 0.7 0.7)
					(thickness 0.15)
				)
				(justify left bottom mirror)
			)
		)
		(fp_text user "License: Apache-2.0"
			(at -1.682 -5.895 270)
			(layer "B.Fab")
			(effects
				(font
					(size 0.7 0.7)
					(thickness 0.15)
				)
				(justify left bottom mirror)
			)
		)
		(pad "1" smd roundrect
			(at -0.7 0 90)
			(size 0.8 1)
			(layers "B.Cu" "B.Mask" "B.Paste")
			(roundrect_rratio 0.2)
			(net 820 "+0V9_MGTAVCC")
			(pintype "passive")
		)
		(pad "2" smd roundrect
			(at 0.7 0 90)
			(size 0.8 1)
			(layers "B.Cu" "B.Mask" "B.Paste")
			(roundrect_rratio 0.2)
			(net 1 "GND")
			(pintype "passive")
		)
	)
	(footprint "antmicro-footprints:C_0402_1005Metric_EIA"
		(layer "B.Cu")
		(at 201 158.5 -90)
		(descr "Capacitor SMD 0402 (1005 Metric), square (rectangular) end terminal, IPC_7351 nominal, (Body size source: IPC-SM-782 page 76, https://www.pcb-3d.com/wordpress/wp-content/uploads/ipc-sm-782a_amendment_1_and_2.pdf)")
		(tags "capacitor 0402")
		(property "Reference" "C108"
			(at 1 -0.425 90)
			(layer "B.SilkS")
			(effects
				(font
					(size 0.7 0.7)
					(thickness 0.15)
				)
				(justify left bottom mirror)
			)
		)
		(property "Value" "C_100n_0402"
			(at 0 -1.169 90)
			(layer "B.Fab")
			(effects
				(font
					(size 0.7 0.7)
					(thickness 0.15)
				)
				(justify left bottom mirror)
			)
		)
		(property "Datasheet" "https://www.murata.com/products/productdetail?partno=GRM155R61H104KE14%23"
			(at 0 0 270)
			(layer "F.Fab")
			(hide yes)
			(effects
				(font
					(size 1.27 1.27)
					(thickness 0.15)
				)
			)
		)
		(property "MPN" "GRM155R61H104KE14D"
			(at 0 0 270)
			(unlocked yes)
			(layer "B.Fab")
			(hide yes)
			(effects
				(font
					(size 1 1)
					(thickness 0.15)
				)
				(justify mirror)
			)
		)
		(property "Manufacturer" "Murata"
			(at 0 0 270)
			(unlocked yes)
			(layer "B.Fab")
			(hide yes)
			(effects
				(font
					(size 1 1)
					(thickness 0.15)
				)
				(justify mirror)
			)
		)
		(property "License" "Apache-2.0"
			(at 0 0 270)
			(unlocked yes)
			(layer "B.Fab")
			(hide yes)
			(effects
				(font
					(size 1 1)
					(thickness 0.15)
				)
				(justify mirror)
			)
		)
		(property "Author" "Antmicro"
			(at 0 0 270)
			(unlocked yes)
			(layer "B.Fab")
			(hide yes)
			(effects
				(font
					(size 1 1)
					(thickness 0.15)
				)
				(justify mirror)
			)
		)
		(property "Val" "100n"
			(at 0 0 270)
			(unlocked yes)
			(layer "B.Fab")
			(hide yes)
			(effects
				(font
					(size 1 1)
					(thickness 0.15)
				)
				(justify mirror)
			)
		)
		(property "Voltage" "50V"
			(at 0 0 270)
			(unlocked yes)
			(layer "B.Fab")
			(hide yes)
			(effects
				(font
					(size 1 1)
					(thickness 0.15)
				)
				(justify mirror)
			)
		)
		(property "Dielectric" "X5R"
			(at 0 0 270)
			(unlocked yes)
			(layer "B.Fab")
			(hide yes)
			(effects
				(font
					(size 1 1)
					(thickness 0.15)
				)
				(justify mirror)
			)
		)
		(sheetname "/FPGA power/")
		(sheetfile "fpga-power.kicad_sch")
		(attr smd)
		(fp_rect
			(start -0.95 0.45)
			(end 0.95 -0.45)
			(stroke
				(width 0.05)
				(type default)
			)
			(fill no)
			(layer "B.CrtYd")
		)
		(fp_line
			(start -0.5 0.25)
			(end 0.498 0.25)
			(stroke
				(width 0.15)
				(type solid)
			)
			(layer "B.Fab")
		)
		(fp_line
			(start 0.498 0.25)
			(end 0.498 -0.248)
			(stroke
				(width 0.15)
				(type solid)
			)
			(layer "B.Fab")
		)
		(fp_line
			(start -0.5 -0.248)
			(end -0.5 0.25)
			(stroke
				(width 0.15)
				(type solid)
			)
			(layer "B.Fab")
		)
		(fp_line
			(start 0.498 -0.248)
			(end -0.5 -0.248)
			(stroke
				(width 0.15)
				(type solid)
			)
			(layer "B.Fab")
		)
		(fp_text user "${REFERENCE}"
			(at -0.9656 -3.169 90)
			(layer "B.Fab")
			(effects
				(font
					(size 0.7 0.7)
					(thickness 0.15)
				)
				(justify left bottom mirror)
			)
		)
		(fp_text user "License: Apache-2.0"
			(at -0.9656 -4.369 90)
			(layer "B.Fab")
			(effects
				(font
					(size 0.7 0.7)
					(thickness 0.15)
				)
				(justify left bottom mirror)
			)
		)
		(fp_text user "Author: Antmicro"
			(at -0.9656 -5.569 90)
			(layer "B.Fab")
			(effects
				(font
					(size 0.7 0.7)
					(thickness 0.15)
				)
				(justify left bottom mirror)
			)
		)
		(pad "1" smd roundrect
			(at -0.5 0 180)
			(size 0.6 0.6)
			(layers "B.Cu" "B.Mask" "B.Paste")
			(roundrect_rratio 0.25)
			(net 1 "GND")
			(pintype "passive")
		)
		(pad "2" smd roundrect
			(at 0.498 0 270)
			(size 0.6 0.6)
			(layers "B.Cu" "B.Mask" "B.Paste")
			(roundrect_rratio 0.25)
			(net 172 "+1V2_MGTAVTT")
			(pintype "passive")
		)
	)
	(footprint "antmicro-footprints:C_0402_1005Metric"
		(layer "B.Cu")
		(at 255.289499 139.25)
		(descr "Capacitor SMD 0402")
		(tags "capacitor SMD 0402")
		(property "Reference" "C209"
			(at 1.410501 0.45 0)
			(layer "B.SilkS")
			(effects
				(font
					(size 0.7 0.7)
					(thickness 0.15)
				)
				(justify right bottom mirror)
			)
		)
		(property "Value" "C_100n_0402"
			(at -1.022927 -2.155213 0)
			(layer "B.Fab")
			(effects
				(font
					(size 0.7 0.7)
					(thickness 0.15)
				)
				(justify right bottom mirror)
			)
		)
		(property "Datasheet" "https://www.murata.com/products/productdetail?partno=GRM155R61H104KE14%23"
			(at 0 0 0)
			(layer "F.Fab")
			(hide yes)
			(effects
				(font
					(size 1.27 1.27)
					(thickness 0.15)
				)
			)
		)
		(property "Manufacturer" "Murata"
			(at 0 0 0)
			(unlocked yes)
			(layer "B.Fab")
			(hide yes)
			(effects
				(font
					(size 1 1)
					(thickness 0.15)
				)
				(justify mirror)
			)
		)
		(property "MPN" "GRM155R61H104KE14D"
			(at 0 0 0)
			(unlocked yes)
			(layer "B.Fab")
			(hide yes)
			(effects
				(font
					(size 1 1)
					(thickness 0.15)
				)
				(justify mirror)
			)
		)
		(property "Val" "100n"
			(at 0 0 0)
			(unlocked yes)
			(layer "B.Fab")
			(hide yes)
			(effects
				(font
					(size 1 1)
					(thickness 0.15)
				)
				(justify mirror)
			)
		)
		(property "License" "Apache-2.0"
			(at 0 0 0)
			(unlocked yes)
			(layer "B.Fab")
			(hide yes)
			(effects
				(font
					(size 1 1)
					(thickness 0.15)
				)
				(justify mirror)
			)
		)
		(property "Author" "Antmicro"
			(at 0 0 0)
			(unlocked yes)
			(layer "B.Fab")
			(hide yes)
			(effects
				(font
					(size 1 1)
					(thickness 0.15)
				)
				(justify mirror)
			)
		)
		(property "Voltage" "50V"
			(at 0 0 0)
			(unlocked yes)
			(layer "B.Fab")
			(hide yes)
			(effects
				(font
					(size 1 1)
					(thickness 0.15)
				)
				(justify mirror)
			)
		)
		(property "Dielectric" "X5R"
			(at 0 0 0)
			(unlocked yes)
			(layer "B.Fab")
			(hide yes)
			(effects
				(font
					(size 1 1)
					(thickness 0.15)
				)
				(justify mirror)
			)
		)
		(sheetname "/Supply/")
		(sheetfile "supply.kicad_sch")
		(attr smd)
		(fp_rect
			(start -0.925 0.47)
			(end 0.925 -0.47)
			(stroke
				(width 0.05)
				(type default)
			)
			(fill no)
			(layer "B.CrtYd")
		)
		(fp_line
			(start -0.494 -0.248)
			(end -0.494 0.25)
			(stroke
				(width 0.15)
				(type solid)
			)
			(layer "B.Fab")
		)
		(fp_line
			(start -0.494 0.25)
			(end 0.504 0.25)
			(stroke
				(width 0.15)
				(type solid)
			)
			(layer "B.Fab")
		)
		(fp_line
			(start 0.504 -0.248)
			(end -0.494 -0.248)
			(stroke
				(width 0.15)
				(type solid)
			)
			(layer "B.Fab")
		)
		(fp_line
			(start 0.504 0.25)
			(end 0.504 -0.248)
			(stroke
				(width 0.15)
				(type solid)
			)
			(layer "B.Fab")
		)
		(fp_text user "License: Apache-2.0"
			(at -0.939 -5.799 180)
			(layer "B.Fab")
			(effects
				(font
					(size 0.7 0.7)
					(thickness 0.15)
				)
				(justify left bottom mirror)
			)
		)
		(fp_text user "Author: Antmicro"
			(at -0.939 -3.399 180)
			(layer "B.Fab")
			(effects
				(font
					(size 0.7 0.7)
					(thickness 0.15)
				)
				(justify left bottom mirror)
			)
		)
		(fp_text user "${REFERENCE}"
			(at -0.939 -4.599 180)
			(layer "B.Fab")
			(effects
				(font
					(size 0.7 0.7)
					(thickness 0.15)
				)
				(justify left bottom mirror)
			)
		)
		(pad "1" smd roundrect
			(at -0.48 0)
			(size 0.59 0.64)
			(layers "B.Cu" "B.Mask" "B.Paste")
			(roundrect_rratio 0.25)
			(net 1 "GND")
			(pintype "passive")
		)
		(pad "2" smd roundrect
			(at 0.48 0)
			(size 0.59 0.64)
			(layers "B.Cu" "B.Mask" "B.Paste")
			(roundrect_rratio 0.25)
			(net 625 "Net-(Q17-D)")
			(pintype "passive")
		)
	)
	(footprint "antmicro-footprints:C_0402_1005Metric_EIA"
		(layer "B.Cu")
		(at 184 154.500001 90)
		(descr "Capacitor SMD 0402 (1005 Metric), square (rectangular) end terminal, IPC_7351 nominal, (Body size source: IPC-SM-782 page 76, https://www.pcb-3d.com/wordpress/wp-content/uploads/ipc-sm-782a_amendment_1_and_2.pdf)")
		(tags "capacitor 0402")
		(property "Reference" "C26"
			(at 10.025001 -30.625 90)
			(layer "B.SilkS")
			(effects
				(font
					(size 0.7 0.7)
					(thickness 0.15)
				)
				(justify right bottom mirror)
			)
		)
		(property "Value" "C_100n_0402"
			(at 0 -1.169 90)
			(layer "B.Fab")
			(effects
				(font
					(size 0.7 0.7)
					(thickness 0.15)
				)
				(justify right bottom mirror)
			)
		)
		(property "Datasheet" "https://www.murata.com/products/productdetail?partno=GRM155R61H104KE14%23"
			(at 0 0 90)
			(layer "F.Fab")
			(hide yes)
			(effects
				(font
					(size 1.27 1.27)
					(thickness 0.15)
				)
			)
		)
		(property "MPN" "GRM155R61H104KE14D"
			(at 0 0 90)
			(unlocked yes)
			(layer "B.Fab")
			(hide yes)
			(effects
				(font
					(size 1 1)
					(thickness 0.15)
				)
				(justify mirror)
			)
		)
		(property "Manufacturer" "Murata"
			(at 0 0 90)
			(unlocked yes)
			(layer "B.Fab")
			(hide yes)
			(effects
				(font
					(size 1 1)
					(thickness 0.15)
				)
				(justify mirror)
			)
		)
		(property "License" "Apache-2.0"
			(at 0 0 90)
			(unlocked yes)
			(layer "B.Fab")
			(hide yes)
			(effects
				(font
					(size 1 1)
					(thickness 0.15)
				)
				(justify mirror)
			)
		)
		(property "Author" "Antmicro"
			(at 0 0 90)
			(unlocked yes)
			(layer "B.Fab")
			(hide yes)
			(effects
				(font
					(size 1 1)
					(thickness 0.15)
				)
				(justify mirror)
			)
		)
		(property "Val" "100n"
			(at 0 0 90)
			(unlocked yes)
			(layer "B.Fab")
			(hide yes)
			(effects
				(font
					(size 1 1)
					(thickness 0.15)
				)
				(justify mirror)
			)
		)
		(property "Voltage" "50V"
			(at 0 0 90)
			(unlocked yes)
			(layer "B.Fab")
			(hide yes)
			(effects
				(font
					(size 1 1)
					(thickness 0.15)
				)
				(justify mirror)
			)
		)
		(property "Dielectric" "X5R"
			(at 0 0 90)
			(unlocked yes)
			(layer "B.Fab")
			(hide yes)
			(effects
				(font
					(size 1 1)
					(thickness 0.15)
				)
				(justify mirror)
			)
		)
		(sheetname "/FPGA power/")
		(sheetfile "fpga-power.kicad_sch")
		(attr smd)
		(fp_rect
			(start -0.95 0.45)
			(end 0.95 -0.45)
			(stroke
				(width 0.05)
				(type default)
			)
			(fill no)
			(layer "B.CrtYd")
		)
		(fp_line
			(start 0.498 -0.248)
			(end -0.5 -0.248)
			(stroke
				(width 0.15)
				(type solid)
			)
			(layer "B.Fab")
		)
		(fp_line
			(start -0.5 -0.248)
			(end -0.5 0.25)
			(stroke
				(width 0.15)
				(type solid)
			)
			(layer "B.Fab")
		)
		(fp_line
			(start 0.498 0.25)
			(end 0.498 -0.248)
			(stroke
				(width 0.15)
				(type solid)
			)
			(layer "B.Fab")
		)
		(fp_line
			(start -0.5 0.25)
			(end 0.498 0.25)
			(stroke
				(width 0.15)
				(type solid)
			)
			(layer "B.Fab")
		)
		(fp_text user "${REFERENCE}"
			(at -0.9656 -3.169 270)
			(layer "B.Fab")
			(effects
				(font
					(size 0.7 0.7)
					(thickness 0.15)
				)
				(justify left bottom mirror)
			)
		)
		(fp_text user "Author: Antmicro"
			(at -0.9656 -5.569 270)
			(layer "B.Fab")
			(effects
				(font
					(size 0.7 0.7)
					(thickness 0.15)
				)
				(justify left bottom mirror)
			)
		)
		(fp_text user "License: Apache-2.0"
			(at -0.9656 -4.369 270)
			(layer "B.Fab")
			(effects
				(font
					(size 0.7 0.7)
					(thickness 0.15)
				)
				(justify left bottom mirror)
			)
		)
		(pad "1" smd roundrect
			(at -0.5 0)
			(size 0.6 0.6)
			(layers "B.Cu" "B.Mask" "B.Paste")
			(roundrect_rratio 0.25)
			(net 1 "GND")
			(pintype "passive")
		)
		(pad "2" smd roundrect
			(at 0.498 0 90)
			(size 0.6 0.6)
			(layers "B.Cu" "B.Mask" "B.Paste")
			(roundrect_rratio 0.25)
			(net 553 "+0V85")
			(pintype "passive")
		)
	)
)
